FILE_TYPE = MACRO_DRAWING;
SET COLOR_WIRE YELLOW;
SET COLOR_PROP ORANGE;
SET COLOR_DOT WHITE;
SET COLOR_ARC YELLOW;
SET COLOR_BODY GREEN;
SET COLOR_NOTE PURPLE;
SET PROP_DISPLAY VALUE;
SET PAGE_NUMBER P382;
FORCEADD TAP..1
(-6825 4575);
FORCEPROP 3 LASTPIN (-6875 4575) SIG_NAME P5E_CPU0_P0_RX_DP<12>
J 0
(-6865 4585);
DISPLAY 0.659574 (-6865 4585);
PAINT MONO (-6865 4585);
DISPLAY INVISIBLE (-6865 4585);
FORCEPROP 1 LASTPIN (-6875 4575) BN 12
J 0
(-6887 4583);
DISPLAY 0.680851 (-6887 4583);
PAINT GREEN (-6887 4583);
FORCEPROP 2 LAST CDS_LIB standard
J 0
(-6825 4575);
DISPLAY INVISIBLE (-6825 4575);
FORCEPROP 1 LAST BODY_TYPE PLUMBING
J 0
(-6825 4625);
DISPLAY 0.872340 (-6825 4625);
PAINT GREEN (-6825 4625);
DISPLAY INVISIBLE (-6825 4625);
FORCEPROP 1 LAST HDL_TAP TRUE
J 0
(-6500 4450);
DISPLAY 0.872340 (-6500 4450);
DISPLAY INVISIBLE (-6500 4450);
FORCEPROP 1 LAST PATH I10
J 0
(-6827 4575);
DISPLAY 0.872340 (-6827 4575);
PAINT GREEN (-6827 4575);
DISPLAY INVISIBLE (-6827 4575);
FORCEADD TAP..1
(-6625 4475);
FORCEPROP 3 LASTPIN (-6675 4475) SIG_NAME P5E_CPU0_P0_RX_DN<12>
J 0
(-6665 4485);
DISPLAY 0.659574 (-6665 4485);
PAINT MONO (-6665 4485);
DISPLAY INVISIBLE (-6665 4485);
FORCEPROP 1 LASTPIN (-6675 4475) BN 12
J 0
(-6687 4483);
DISPLAY 0.680851 (-6687 4483);
PAINT GREEN (-6687 4483);
FORCEPROP 2 LAST CDS_LIB standard
J 0
(-6625 4475);
DISPLAY INVISIBLE (-6625 4475);
FORCEPROP 1 LAST BODY_TYPE PLUMBING
J 0
(-6625 4525);
DISPLAY 0.872340 (-6625 4525);
PAINT GREEN (-6625 4525);
DISPLAY INVISIBLE (-6625 4525);
FORCEPROP 1 LAST HDL_TAP TRUE
J 0
(-6300 4350);
DISPLAY 0.872340 (-6300 4350);
DISPLAY INVISIBLE (-6300 4350);
FORCEPROP 1 LAST PATH I11
J 0
(-6627 4475);
DISPLAY 0.872340 (-6627 4475);
PAINT GREEN (-6627 4475);
DISPLAY INVISIBLE (-6627 4475);
FORCEADD TAP..1
(-6825 4925);
FORCEPROP 3 LASTPIN (-6875 4925) SIG_NAME P5E_CPU0_P0_RX_DP<13>
J 0
(-6865 4935);
DISPLAY 0.659574 (-6865 4935);
PAINT MONO (-6865 4935);
DISPLAY INVISIBLE (-6865 4935);
FORCEPROP 1 LASTPIN (-6875 4925) BN 13
J 0
(-6887 4933);
DISPLAY 0.680851 (-6887 4933);
PAINT GREEN (-6887 4933);
FORCEPROP 2 LAST CDS_LIB standard
J 0
(-6825 4925);
DISPLAY INVISIBLE (-6825 4925);
FORCEPROP 1 LAST BODY_TYPE PLUMBING
J 0
(-6825 4975);
DISPLAY 0.872340 (-6825 4975);
PAINT GREEN (-6825 4975);
DISPLAY INVISIBLE (-6825 4975);
FORCEPROP 1 LAST HDL_TAP TRUE
J 0
(-6500 4800);
DISPLAY 0.872340 (-6500 4800);
DISPLAY INVISIBLE (-6500 4800);
FORCEPROP 1 LAST PATH I12
J 0
(-6827 4925);
DISPLAY 0.872340 (-6827 4925);
PAINT GREEN (-6827 4925);
DISPLAY INVISIBLE (-6827 4925);
FORCEADD TAP..1
(-6625 4825);
FORCEPROP 3 LASTPIN (-6675 4825) SIG_NAME P5E_CPU0_P0_RX_DN<13>
J 0
(-6665 4835);
DISPLAY 0.659574 (-6665 4835);
PAINT MONO (-6665 4835);
DISPLAY INVISIBLE (-6665 4835);
FORCEPROP 1 LASTPIN (-6675 4825) BN 13
J 0
(-6687 4833);
DISPLAY 0.680851 (-6687 4833);
PAINT GREEN (-6687 4833);
FORCEPROP 2 LAST CDS_LIB standard
J 0
(-6625 4825);
DISPLAY INVISIBLE (-6625 4825);
FORCEPROP 1 LAST BODY_TYPE PLUMBING
J 0
(-6625 4875);
DISPLAY 0.872340 (-6625 4875);
PAINT GREEN (-6625 4875);
DISPLAY INVISIBLE (-6625 4875);
FORCEPROP 1 LAST HDL_TAP TRUE
J 0
(-6300 4700);
DISPLAY 0.872340 (-6300 4700);
DISPLAY INVISIBLE (-6300 4700);
FORCEPROP 1 LAST PATH I13
J 0
(-6627 4825);
DISPLAY 0.872340 (-6627 4825);
PAINT GREEN (-6627 4825);
DISPLAY INVISIBLE (-6627 4825);
FORCEADD TAP..1
(-6625 5175);
FORCEPROP 3 LASTPIN (-6675 5175) SIG_NAME P5E_CPU0_P0_RX_DN<14>
J 0
(-6665 5185);
DISPLAY 0.659574 (-6665 5185);
PAINT MONO (-6665 5185);
DISPLAY INVISIBLE (-6665 5185);
FORCEPROP 1 LASTPIN (-6675 5175) BN 14
J 0
(-6687 5183);
DISPLAY 0.680851 (-6687 5183);
PAINT GREEN (-6687 5183);
FORCEPROP 2 LAST CDS_LIB standard
J 0
(-6625 5175);
DISPLAY INVISIBLE (-6625 5175);
FORCEPROP 1 LAST BODY_TYPE PLUMBING
J 0
(-6625 5225);
DISPLAY 0.872340 (-6625 5225);
PAINT GREEN (-6625 5225);
DISPLAY INVISIBLE (-6625 5225);
FORCEPROP 1 LAST HDL_TAP TRUE
J 0
(-6300 5050);
DISPLAY 0.872340 (-6300 5050);
DISPLAY INVISIBLE (-6300 5050);
FORCEPROP 1 LAST PATH I14
J 0
(-6627 5175);
DISPLAY 0.872340 (-6627 5175);
PAINT GREEN (-6627 5175);
DISPLAY INVISIBLE (-6627 5175);
FORCEADD TAP..1
(-6825 5275);
FORCEPROP 3 LASTPIN (-6875 5275) SIG_NAME P5E_CPU0_P0_RX_DP<14>
J 0
(-6865 5285);
DISPLAY 0.659574 (-6865 5285);
PAINT MONO (-6865 5285);
DISPLAY INVISIBLE (-6865 5285);
FORCEPROP 1 LASTPIN (-6875 5275) BN 14
J 0
(-6887 5283);
DISPLAY 0.680851 (-6887 5283);
PAINT GREEN (-6887 5283);
FORCEPROP 2 LAST CDS_LIB standard
J 0
(-6825 5275);
DISPLAY INVISIBLE (-6825 5275);
FORCEPROP 1 LAST BODY_TYPE PLUMBING
J 0
(-6825 5325);
DISPLAY 0.872340 (-6825 5325);
PAINT GREEN (-6825 5325);
DISPLAY INVISIBLE (-6825 5325);
FORCEPROP 1 LAST HDL_TAP TRUE
J 0
(-6500 5150);
DISPLAY 0.872340 (-6500 5150);
DISPLAY INVISIBLE (-6500 5150);
FORCEPROP 1 LAST PATH I15
J 0
(-6827 5275);
DISPLAY 0.872340 (-6827 5275);
PAINT GREEN (-6827 5275);
DISPLAY INVISIBLE (-6827 5275);
FORCEADD TAP..1
(-6825 5625);
FORCEPROP 3 LASTPIN (-6875 5625) SIG_NAME P5E_CPU0_P0_RX_DP<15>
J 0
(-6865 5635);
DISPLAY 0.659574 (-6865 5635);
PAINT MONO (-6865 5635);
DISPLAY INVISIBLE (-6865 5635);
FORCEPROP 1 LASTPIN (-6875 5625) BN 15
J 0
(-6887 5633);
DISPLAY 0.680851 (-6887 5633);
PAINT GREEN (-6887 5633);
FORCEPROP 2 LAST CDS_LIB standard
J 0
(-6825 5625);
DISPLAY INVISIBLE (-6825 5625);
FORCEPROP 1 LAST BODY_TYPE PLUMBING
J 0
(-6825 5675);
DISPLAY 0.872340 (-6825 5675);
PAINT GREEN (-6825 5675);
DISPLAY INVISIBLE (-6825 5675);
FORCEPROP 1 LAST HDL_TAP TRUE
J 0
(-6500 5500);
DISPLAY 0.872340 (-6500 5500);
DISPLAY INVISIBLE (-6500 5500);
FORCEPROP 1 LAST PATH I16
J 0
(-6827 5625);
DISPLAY 0.872340 (-6827 5625);
PAINT GREEN (-6827 5625);
DISPLAY INVISIBLE (-6827 5625);
FORCEADD TAP..1
(-6625 5525);
FORCEPROP 3 LASTPIN (-6675 5525) SIG_NAME P5E_CPU0_P0_RX_DN<15>
J 0
(-6665 5535);
DISPLAY 0.659574 (-6665 5535);
PAINT MONO (-6665 5535);
DISPLAY INVISIBLE (-6665 5535);
FORCEPROP 1 LASTPIN (-6675 5525) BN 15
J 0
(-6687 5533);
DISPLAY 0.680851 (-6687 5533);
PAINT GREEN (-6687 5533);
FORCEPROP 2 LAST CDS_LIB standard
J 0
(-6625 5525);
DISPLAY INVISIBLE (-6625 5525);
FORCEPROP 1 LAST BODY_TYPE PLUMBING
J 0
(-6625 5575);
DISPLAY 0.872340 (-6625 5575);
PAINT GREEN (-6625 5575);
DISPLAY INVISIBLE (-6625 5575);
FORCEPROP 1 LAST HDL_TAP TRUE
J 0
(-6300 5400);
DISPLAY 0.872340 (-6300 5400);
DISPLAY INVISIBLE (-6300 5400);
FORCEPROP 1 LAST PATH I17
J 0
(-6627 5525);
DISPLAY 0.872340 (-6627 5525);
PAINT GREEN (-6627 5525);
DISPLAY INVISIBLE (-6627 5525);
FORCEADD PT5161LRS..6
(-7850 4375);
FORCEPROP 1 LAST LOCATION U6010
J 0
(-8200 6000);
DISPLAY 0.723404 (-8200 6000);
PAINT GREEN (-8200 6000);
FORCEPROP 0 LAST $SEC 6
J 0
(-8200 6150);
DISPLAY 0.680851 (-8200 6150);
PAINT MONO (-8200 6150);
DISPLAY INVISIBLE (-8200 6150);
FORCEPROP 0 LAST CDS_SEC 6
J 0
(-8200 6150);
DISPLAY 0.680851 (-8200 6150);
DISPLAY INVISIBLE (-8200 6150);
FORCEPROP 0 LASTPIN (-7400 5525) $PN P29
J 0
(-7390 5535);
DISPLAY 0.680851 (-7390 5535);
PAINT MONO (-7390 5535);
FORCEPROP 0 LASTPIN (-7400 5175) $PN AA29
J 0
(-7390 5185);
DISPLAY 0.680851 (-7390 5185);
PAINT MONO (-7390 5185);
FORCEPROP 0 LASTPIN (-7400 4825) $PN AH29
J 0
(-7390 4835);
DISPLAY 0.680851 (-7390 4835);
PAINT MONO (-7390 4835);
FORCEPROP 0 LASTPIN (-7400 4475) $PN AR29
J 0
(-7390 4485);
DISPLAY 0.680851 (-7390 4485);
PAINT MONO (-7390 4485);
FORCEPROP 0 LASTPIN (-7400 4125) $PN BB29
J 0
(-7390 4135);
DISPLAY 0.680851 (-7390 4135);
PAINT MONO (-7390 4135);
FORCEPROP 0 LASTPIN (-7400 3775) $PN BJ29
J 0
(-7390 3785);
DISPLAY 0.680851 (-7390 3785);
PAINT MONO (-7390 3785);
FORCEPROP 0 LASTPIN (-7400 3425) $PN BT29
J 0
(-7390 3435);
DISPLAY 0.680851 (-7390 3435);
PAINT MONO (-7390 3435);
FORCEPROP 0 LASTPIN (-7400 3075) $PN CC29
J 0
(-7390 3085);
DISPLAY 0.680851 (-7390 3085);
PAINT MONO (-7390 3085);
FORCEPROP 0 LASTPIN (-7400 5625) $PN M26
J 0
(-7390 5635);
DISPLAY 0.680851 (-7390 5635);
PAINT MONO (-7390 5635);
FORCEPROP 0 LASTPIN (-7400 5275) $PN W26
J 0
(-7390 5285);
DISPLAY 0.680851 (-7390 5285);
PAINT MONO (-7390 5285);
FORCEPROP 0 LASTPIN (-7400 4925) $PN AF26
J 0
(-7390 4935);
DISPLAY 0.680851 (-7390 4935);
PAINT MONO (-7390 4935);
FORCEPROP 0 LASTPIN (-7400 4575) $PN AN26
J 0
(-7390 4585);
DISPLAY 0.680851 (-7390 4585);
PAINT MONO (-7390 4585);
FORCEPROP 0 LASTPIN (-7400 4225) $PN AY26
J 0
(-7390 4235);
DISPLAY 0.680851 (-7390 4235);
PAINT MONO (-7390 4235);
FORCEPROP 0 LASTPIN (-7400 3875) $PN BG26
J 0
(-7390 3885);
DISPLAY 0.680851 (-7390 3885);
PAINT MONO (-7390 3885);
FORCEPROP 0 LASTPIN (-7400 3525) $PN BP26
J 0
(-7390 3535);
DISPLAY 0.680851 (-7390 3535);
PAINT MONO (-7390 3535);
FORCEPROP 0 LASTPIN (-7400 3175) $PN CA26
J 0
(-7390 3185);
DISPLAY 0.680851 (-7390 3185);
PAINT MONO (-7390 3185);
FORCEPROP 1 LAST MATERIAL IC
J 0
(-8200 5850);
DISPLAY 0.723404 (-8200 5850);
PAINT GREEN (-8200 5850);
FORCEPROP 2 LAST VALUE PT5161LRS
J 0
(-8200 6050);
DISPLAY 0.680851 (-8200 6050);
FORCEPROP 2 LAST PART_TYPE SMLF
J 0
(-8200 6100);
DISPLAY 0.680851 (-8200 6100);
FORCEPROP 1 LAST NEEDS_NO_SIZE TRUE
J 0
(-7850 4375);
DISPLAY 0.723404 (-7850 4375);
PAINT GREEN (-7850 4375);
DISPLAY INVISIBLE (-7850 4375);
FORCEPROP 1 LAST CDS_LMAN_SYM_OUTLINE -350,1450,300,-1400
J 0
(-7850 4375);
DISPLAY 0.468085 (-7850 4375);
PAINT GREEN (-7850 4375);
DISPLAY INVISIBLE (-7850 4375);
FORCEPROP 2 LAST CDS_LIB pure_quanta
J 0
(-7850 4375);
DISPLAY INVISIBLE (-7850 4375);
FORCEPROP 1 LAST PATH I2
J 0
(-7850 4375);
DISPLAY 0.723404 (-7850 4375);
PAINT GREEN (-7850 4375);
DISPLAY INVISIBLE (-7850 4375);
FORCEPROP 1 LAST PART_NUMBER AJ051610U03
J 0
(-8200 5925);
DISPLAY 0.723404 (-8200 5925);
PAINT GREEN (-8200 5925);
DISPLAY INVISIBLE (-8200 5925);
FORCEADD TAP..1
(-6825 3175);
FORCEPROP 3 LASTPIN (-6875 3175) SIG_NAME P5E_CPU0_P0_RX_DP<8>
J 0
(-6865 3185);
DISPLAY 0.659574 (-6865 3185);
PAINT MONO (-6865 3185);
DISPLAY INVISIBLE (-6865 3185);
FORCEPROP 1 LASTPIN (-6875 3175) BN 8
J 0
(-6887 3183);
DISPLAY 0.680851 (-6887 3183);
PAINT GREEN (-6887 3183);
FORCEPROP 2 LAST CDS_LIB standard
J 0
(-6825 3175);
DISPLAY INVISIBLE (-6825 3175);
FORCEPROP 1 LAST BODY_TYPE PLUMBING
J 0
(-6825 3225);
DISPLAY 0.872340 (-6825 3225);
PAINT GREEN (-6825 3225);
DISPLAY INVISIBLE (-6825 3225);
FORCEPROP 1 LAST HDL_TAP TRUE
J 0
(-6500 3050);
DISPLAY 0.872340 (-6500 3050);
DISPLAY INVISIBLE (-6500 3050);
FORCEPROP 1 LAST PATH I20
J 0
(-6827 3175);
DISPLAY 0.872340 (-6827 3175);
PAINT GREEN (-6827 3175);
DISPLAY INVISIBLE (-6827 3175);
FORCEADD TAP..1
(-6625 3425);
FORCEPROP 3 LASTPIN (-6675 3425) SIG_NAME P5E_CPU0_P0_RX_DN<9>
J 0
(-6665 3435);
DISPLAY 0.659574 (-6665 3435);
PAINT MONO (-6665 3435);
DISPLAY INVISIBLE (-6665 3435);
FORCEPROP 1 LASTPIN (-6675 3425) BN 9
J 0
(-6687 3433);
DISPLAY 0.680851 (-6687 3433);
PAINT GREEN (-6687 3433);
FORCEPROP 2 LAST CDS_LIB standard
J 0
(-6625 3425);
DISPLAY INVISIBLE (-6625 3425);
FORCEPROP 1 LAST BODY_TYPE PLUMBING
J 0
(-6625 3475);
DISPLAY 0.872340 (-6625 3475);
PAINT GREEN (-6625 3475);
DISPLAY INVISIBLE (-6625 3475);
FORCEPROP 1 LAST HDL_TAP TRUE
J 0
(-6300 3300);
DISPLAY 0.872340 (-6300 3300);
DISPLAY INVISIBLE (-6300 3300);
FORCEPROP 1 LAST PATH I21
J 0
(-6627 3425);
DISPLAY 0.872340 (-6627 3425);
PAINT GREEN (-6627 3425);
DISPLAY INVISIBLE (-6627 3425);
FORCEADD OFFPAGE..5
R 2
(-5600 5725);
FORCEPROP 2 LAST $XR0 24 
J 0
(-5411 5725);
DISPLAY 0.638298 (-5411 5725);
PAINT MONO (-5411 5725);
FORCEPROP 2 LAST CDS_LIB standard
J 0
(-5600 5725);
DISPLAY INVISIBLE (-5600 5725);
FORCEPROP 1 LAST OFFPAGE TRUE
J 2
(-5925 5600);
DISPLAY 0.872340 (-5925 5600);
PAINT GREEN (-5925 5600);
DISPLAY INVISIBLE (-5925 5600);
FORCEPROP 1 LAST COMMENT_BODY TRUE
J 2
(-5700 5650);
DISPLAY 0.872340 (-5700 5650);
PAINT GREEN (-5700 5650);
DISPLAY INVISIBLE (-5700 5650);
FORCEPROP 2 LAST PATH I22
J 0
(-5425 5800);
DISPLAY 0.680851 (-5425 5800);
DISPLAY INVISIBLE (-5425 5800);
FORCEADD OFFPAGE..5
R 2
(-5625 5600);
FORCEPROP 2 LAST $XR0 24 
J 0
(-5436 5600);
DISPLAY 0.638298 (-5436 5600);
PAINT MONO (-5436 5600);
FORCEPROP 2 LAST CDS_LIB standard
J 0
(-5625 5600);
DISPLAY INVISIBLE (-5625 5600);
FORCEPROP 1 LAST OFFPAGE TRUE
J 2
(-5950 5475);
DISPLAY 0.872340 (-5950 5475);
PAINT GREEN (-5950 5475);
DISPLAY INVISIBLE (-5950 5475);
FORCEPROP 1 LAST COMMENT_BODY TRUE
J 2
(-5725 5525);
DISPLAY 0.872340 (-5725 5525);
PAINT GREEN (-5725 5525);
DISPLAY INVISIBLE (-5725 5525);
FORCEPROP 2 LAST PATH I23
J 0
(-5450 5675);
DISPLAY 0.680851 (-5450 5675);
DISPLAY INVISIBLE (-5450 5675);
FORCEADD TAP..1
(-2450 3200);
FORCEPROP 3 LASTPIN (-2500 3200) SIG_NAME P5E_CPU0_P0_RX_DP<0>
J 0
(-2490 3210);
DISPLAY 0.659574 (-2490 3210);
PAINT MONO (-2490 3210);
DISPLAY INVISIBLE (-2490 3210);
FORCEPROP 1 LASTPIN (-2500 3200) BN 0
J 0
(-2512 3208);
DISPLAY 0.680851 (-2512 3208);
PAINT GREEN (-2512 3208);
FORCEPROP 2 LAST CDS_LIB standard
J 0
(-2450 3200);
DISPLAY INVISIBLE (-2450 3200);
FORCEPROP 1 LAST BODY_TYPE PLUMBING
J 0
(-2450 3250);
DISPLAY 0.872340 (-2450 3250);
PAINT GREEN (-2450 3250);
DISPLAY INVISIBLE (-2450 3250);
FORCEPROP 1 LAST HDL_TAP TRUE
J 0
(-2125 3075);
DISPLAY 0.872340 (-2125 3075);
DISPLAY INVISIBLE (-2125 3075);
FORCEPROP 1 LAST PATH I24
J 0
(-2452 3200);
DISPLAY 0.872340 (-2452 3200);
PAINT GREEN (-2452 3200);
DISPLAY INVISIBLE (-2452 3200);
FORCEADD TAP..1
(-2250 3100);
FORCEPROP 3 LASTPIN (-2300 3100) SIG_NAME P5E_CPU0_P0_RX_DN<0>
J 0
(-2290 3110);
DISPLAY 0.659574 (-2290 3110);
PAINT MONO (-2290 3110);
DISPLAY INVISIBLE (-2290 3110);
FORCEPROP 1 LASTPIN (-2300 3100) BN 0
J 0
(-2312 3108);
DISPLAY 0.680851 (-2312 3108);
PAINT GREEN (-2312 3108);
FORCEPROP 2 LAST CDS_LIB standard
J 0
(-2250 3100);
DISPLAY INVISIBLE (-2250 3100);
FORCEPROP 1 LAST BODY_TYPE PLUMBING
J 0
(-2250 3150);
DISPLAY 0.872340 (-2250 3150);
PAINT GREEN (-2250 3150);
DISPLAY INVISIBLE (-2250 3150);
FORCEPROP 1 LAST HDL_TAP TRUE
J 0
(-1925 2975);
DISPLAY 0.872340 (-1925 2975);
DISPLAY INVISIBLE (-1925 2975);
FORCEPROP 1 LAST PATH I25
J 0
(-2252 3100);
DISPLAY 0.872340 (-2252 3100);
PAINT GREEN (-2252 3100);
DISPLAY INVISIBLE (-2252 3100);
FORCEADD TAP..1
(-2450 3550);
FORCEPROP 3 LASTPIN (-2500 3550) SIG_NAME P5E_CPU0_P0_RX_DP<1>
J 0
(-2490 3560);
DISPLAY 0.659574 (-2490 3560);
PAINT MONO (-2490 3560);
DISPLAY INVISIBLE (-2490 3560);
FORCEPROP 1 LASTPIN (-2500 3550) BN 1
J 0
(-2512 3558);
DISPLAY 0.680851 (-2512 3558);
PAINT GREEN (-2512 3558);
FORCEPROP 2 LAST CDS_LIB standard
J 0
(-2450 3550);
DISPLAY INVISIBLE (-2450 3550);
FORCEPROP 1 LAST BODY_TYPE PLUMBING
J 0
(-2450 3600);
DISPLAY 0.872340 (-2450 3600);
PAINT GREEN (-2450 3600);
DISPLAY INVISIBLE (-2450 3600);
FORCEPROP 1 LAST HDL_TAP TRUE
J 0
(-2125 3425);
DISPLAY 0.872340 (-2125 3425);
DISPLAY INVISIBLE (-2125 3425);
FORCEPROP 1 LAST PATH I26
J 0
(-2452 3550);
DISPLAY 0.872340 (-2452 3550);
PAINT GREEN (-2452 3550);
DISPLAY INVISIBLE (-2452 3550);
FORCEADD TAP..1
(-2250 3450);
FORCEPROP 3 LASTPIN (-2300 3450) SIG_NAME P5E_CPU0_P0_RX_DN<1>
J 0
(-2290 3460);
DISPLAY 0.659574 (-2290 3460);
PAINT MONO (-2290 3460);
DISPLAY INVISIBLE (-2290 3460);
FORCEPROP 1 LASTPIN (-2300 3450) BN 1
J 0
(-2312 3458);
DISPLAY 0.680851 (-2312 3458);
PAINT GREEN (-2312 3458);
FORCEPROP 2 LAST CDS_LIB standard
J 0
(-2250 3450);
DISPLAY INVISIBLE (-2250 3450);
FORCEPROP 1 LAST BODY_TYPE PLUMBING
J 0
(-2250 3500);
DISPLAY 0.872340 (-2250 3500);
PAINT GREEN (-2250 3500);
DISPLAY INVISIBLE (-2250 3500);
FORCEPROP 1 LAST HDL_TAP TRUE
J 0
(-1925 3325);
DISPLAY 0.872340 (-1925 3325);
DISPLAY INVISIBLE (-1925 3325);
FORCEPROP 1 LAST PATH I27
J 0
(-2252 3450);
DISPLAY 0.872340 (-2252 3450);
PAINT GREEN (-2252 3450);
DISPLAY INVISIBLE (-2252 3450);
FORCEADD TAP..1
(-2450 3900);
FORCEPROP 3 LASTPIN (-2500 3900) SIG_NAME P5E_CPU0_P0_RX_DP<2>
J 0
(-2490 3910);
DISPLAY 0.659574 (-2490 3910);
PAINT MONO (-2490 3910);
DISPLAY INVISIBLE (-2490 3910);
FORCEPROP 1 LASTPIN (-2500 3900) BN 2
J 0
(-2512 3908);
DISPLAY 0.680851 (-2512 3908);
PAINT GREEN (-2512 3908);
FORCEPROP 2 LAST CDS_LIB standard
J 0
(-2450 3900);
DISPLAY INVISIBLE (-2450 3900);
FORCEPROP 1 LAST BODY_TYPE PLUMBING
J 0
(-2450 3950);
DISPLAY 0.872340 (-2450 3950);
PAINT GREEN (-2450 3950);
DISPLAY INVISIBLE (-2450 3950);
FORCEPROP 1 LAST HDL_TAP TRUE
J 0
(-2125 3775);
DISPLAY 0.872340 (-2125 3775);
DISPLAY INVISIBLE (-2125 3775);
FORCEPROP 1 LAST PATH I28
J 0
(-2452 3900);
DISPLAY 0.872340 (-2452 3900);
PAINT GREEN (-2452 3900);
DISPLAY INVISIBLE (-2452 3900);
FORCEADD TAP..1
(-2450 4250);
FORCEPROP 3 LASTPIN (-2500 4250) SIG_NAME P5E_CPU0_P0_RX_DP<3>
J 0
(-2490 4260);
DISPLAY 0.659574 (-2490 4260);
PAINT MONO (-2490 4260);
DISPLAY INVISIBLE (-2490 4260);
FORCEPROP 1 LASTPIN (-2500 4250) BN 3
J 0
(-2512 4258);
DISPLAY 0.680851 (-2512 4258);
PAINT GREEN (-2512 4258);
FORCEPROP 2 LAST CDS_LIB standard
J 0
(-2450 4250);
DISPLAY INVISIBLE (-2450 4250);
FORCEPROP 1 LAST BODY_TYPE PLUMBING
J 0
(-2450 4300);
DISPLAY 0.872340 (-2450 4300);
PAINT GREEN (-2450 4300);
DISPLAY INVISIBLE (-2450 4300);
FORCEPROP 1 LAST HDL_TAP TRUE
J 0
(-2125 4125);
DISPLAY 0.872340 (-2125 4125);
DISPLAY INVISIBLE (-2125 4125);
FORCEPROP 1 LAST PATH I29
J 0
(-2452 4250);
DISPLAY 0.872340 (-2452 4250);
PAINT GREEN (-2452 4250);
DISPLAY INVISIBLE (-2452 4250);
FORCEADD PT5161LRS..7
(-3475 4400);
FORCEPROP 1 LAST LOCATION U6010
J 0
(-3825 6025);
DISPLAY 0.723404 (-3825 6025);
PAINT GREEN (-3825 6025);
FORCEPROP 0 LAST $SEC 7
J 0
(-3825 6175);
DISPLAY 0.680851 (-3825 6175);
PAINT MONO (-3825 6175);
DISPLAY INVISIBLE (-3825 6175);
FORCEPROP 0 LAST CDS_SEC 7
J 0
(-3825 6175);
DISPLAY 0.680851 (-3825 6175);
DISPLAY INVISIBLE (-3825 6175);
FORCEPROP 0 LASTPIN (-3025 5550) $PN CK29
J 0
(-3015 5560);
DISPLAY 0.680851 (-3015 5560);
PAINT MONO (-3015 5560);
FORCEPROP 0 LASTPIN (-3025 5200) $PN CU29
J 0
(-3015 5210);
DISPLAY 0.680851 (-3015 5210);
PAINT MONO (-3015 5210);
FORCEPROP 0 LASTPIN (-3025 4850) $PN DD29
J 0
(-3015 4860);
DISPLAY 0.680851 (-3015 4860);
PAINT MONO (-3015 4860);
FORCEPROP 0 LASTPIN (-3025 4500) $PN DL29
J 0
(-3015 4510);
DISPLAY 0.680851 (-3015 4510);
PAINT MONO (-3015 4510);
FORCEPROP 0 LASTPIN (-3025 4150) $PN DV29
J 0
(-3015 4160);
DISPLAY 0.680851 (-3015 4160);
PAINT MONO (-3015 4160);
FORCEPROP 0 LASTPIN (-3025 3800) $PN EE29
J 0
(-3015 3810);
DISPLAY 0.680851 (-3015 3810);
PAINT MONO (-3015 3810);
FORCEPROP 0 LASTPIN (-3025 3450) $PN EM29
J 0
(-3015 3460);
DISPLAY 0.680851 (-3015 3460);
PAINT MONO (-3015 3460);
FORCEPROP 0 LASTPIN (-3025 3100) $PN EW29
J 0
(-3015 3110);
DISPLAY 0.680851 (-3015 3110);
PAINT MONO (-3015 3110);
FORCEPROP 0 LASTPIN (-3025 5650) $PN CH26
J 0
(-3015 5660);
DISPLAY 0.680851 (-3015 5660);
PAINT MONO (-3015 5660);
FORCEPROP 0 LASTPIN (-3025 5300) $PN CR26
J 0
(-3015 5310);
DISPLAY 0.680851 (-3015 5310);
PAINT MONO (-3015 5310);
FORCEPROP 0 LASTPIN (-3025 4950) $PN DB26
J 0
(-3015 4960);
DISPLAY 0.680851 (-3015 4960);
PAINT MONO (-3015 4960);
FORCEPROP 0 LASTPIN (-3025 4600) $PN DJ26
J 0
(-3015 4610);
DISPLAY 0.680851 (-3015 4610);
PAINT MONO (-3015 4610);
FORCEPROP 0 LASTPIN (-3025 4250) $PN DT26
J 0
(-3015 4260);
DISPLAY 0.680851 (-3015 4260);
PAINT MONO (-3015 4260);
FORCEPROP 0 LASTPIN (-3025 3900) $PN EC26
J 0
(-3015 3910);
DISPLAY 0.680851 (-3015 3910);
PAINT MONO (-3015 3910);
FORCEPROP 0 LASTPIN (-3025 3550) $PN EK26
J 0
(-3015 3560);
DISPLAY 0.680851 (-3015 3560);
PAINT MONO (-3015 3560);
FORCEPROP 0 LASTPIN (-3025 3200) $PN EU26
J 0
(-3015 3210);
DISPLAY 0.680851 (-3015 3210);
PAINT MONO (-3015 3210);
FORCEPROP 1 LAST MATERIAL IC
J 0
(-3825 5875);
DISPLAY 0.723404 (-3825 5875);
PAINT GREEN (-3825 5875);
FORCEPROP 2 LAST PART_TYPE SMLF
J 0
(-3825 6125);
DISPLAY 0.680851 (-3825 6125);
FORCEPROP 2 LAST VALUE PT5161LRS
J 0
(-3825 6075);
DISPLAY 0.680851 (-3825 6075);
FORCEPROP 2 LAST CDS_LIB pure_quanta
J 0
(-3475 4400);
DISPLAY INVISIBLE (-3475 4400);
FORCEPROP 1 LAST CDS_LMAN_SYM_OUTLINE -350,1450,300,-1400
J 0
(-3475 4400);
DISPLAY 0.468085 (-3475 4400);
PAINT GREEN (-3475 4400);
DISPLAY INVISIBLE (-3475 4400);
FORCEPROP 1 LAST NEEDS_NO_SIZE TRUE
J 0
(-3475 4400);
DISPLAY 0.723404 (-3475 4400);
PAINT GREEN (-3475 4400);
DISPLAY INVISIBLE (-3475 4400);
FORCEPROP 1 LAST PATH I3
J 0
(-3475 4400);
DISPLAY 0.723404 (-3475 4400);
PAINT GREEN (-3475 4400);
DISPLAY INVISIBLE (-3475 4400);
FORCEPROP 1 LAST PART_NUMBER AJ051610U03
J 0
(-3825 5950);
DISPLAY 0.723404 (-3825 5950);
PAINT GREEN (-3825 5950);
DISPLAY INVISIBLE (-3825 5950);
FORCEADD TAP..1
(-2250 3800);
FORCEPROP 3 LASTPIN (-2300 3800) SIG_NAME P5E_CPU0_P0_RX_DN<2>
J 0
(-2290 3810);
DISPLAY 0.659574 (-2290 3810);
PAINT MONO (-2290 3810);
DISPLAY INVISIBLE (-2290 3810);
FORCEPROP 1 LASTPIN (-2300 3800) BN 2
J 0
(-2312 3808);
DISPLAY 0.680851 (-2312 3808);
PAINT GREEN (-2312 3808);
FORCEPROP 2 LAST CDS_LIB standard
J 0
(-2250 3800);
DISPLAY INVISIBLE (-2250 3800);
FORCEPROP 1 LAST BODY_TYPE PLUMBING
J 0
(-2250 3850);
DISPLAY 0.872340 (-2250 3850);
PAINT GREEN (-2250 3850);
DISPLAY INVISIBLE (-2250 3850);
FORCEPROP 1 LAST HDL_TAP TRUE
J 0
(-1925 3675);
DISPLAY 0.872340 (-1925 3675);
DISPLAY INVISIBLE (-1925 3675);
FORCEPROP 1 LAST PATH I30
J 0
(-2252 3800);
DISPLAY 0.872340 (-2252 3800);
PAINT GREEN (-2252 3800);
DISPLAY INVISIBLE (-2252 3800);
FORCEADD TAP..1
(-2250 4150);
FORCEPROP 3 LASTPIN (-2300 4150) SIG_NAME P5E_CPU0_P0_RX_DN<3>
J 0
(-2290 4160);
DISPLAY 0.659574 (-2290 4160);
PAINT MONO (-2290 4160);
DISPLAY INVISIBLE (-2290 4160);
FORCEPROP 1 LASTPIN (-2300 4150) BN 3
J 0
(-2312 4158);
DISPLAY 0.680851 (-2312 4158);
PAINT GREEN (-2312 4158);
FORCEPROP 2 LAST CDS_LIB standard
J 0
(-2250 4150);
DISPLAY INVISIBLE (-2250 4150);
FORCEPROP 1 LAST BODY_TYPE PLUMBING
J 0
(-2250 4200);
DISPLAY 0.872340 (-2250 4200);
PAINT GREEN (-2250 4200);
DISPLAY INVISIBLE (-2250 4200);
FORCEPROP 1 LAST HDL_TAP TRUE
J 0
(-1925 4025);
DISPLAY 0.872340 (-1925 4025);
DISPLAY INVISIBLE (-1925 4025);
FORCEPROP 1 LAST PATH I31
J 0
(-2252 4150);
DISPLAY 0.872340 (-2252 4150);
PAINT GREEN (-2252 4150);
DISPLAY INVISIBLE (-2252 4150);
FORCEADD TAP..1
(-2450 4600);
FORCEPROP 3 LASTPIN (-2500 4600) SIG_NAME P5E_CPU0_P0_RX_DP<4>
J 0
(-2490 4610);
DISPLAY 0.659574 (-2490 4610);
PAINT MONO (-2490 4610);
DISPLAY INVISIBLE (-2490 4610);
FORCEPROP 1 LASTPIN (-2500 4600) BN 4
J 0
(-2512 4608);
DISPLAY 0.680851 (-2512 4608);
PAINT GREEN (-2512 4608);
FORCEPROP 2 LAST CDS_LIB standard
J 0
(-2450 4600);
DISPLAY INVISIBLE (-2450 4600);
FORCEPROP 1 LAST BODY_TYPE PLUMBING
J 0
(-2450 4650);
DISPLAY 0.872340 (-2450 4650);
PAINT GREEN (-2450 4650);
DISPLAY INVISIBLE (-2450 4650);
FORCEPROP 1 LAST HDL_TAP TRUE
J 0
(-2125 4475);
DISPLAY 0.872340 (-2125 4475);
DISPLAY INVISIBLE (-2125 4475);
FORCEPROP 1 LAST PATH I32
J 0
(-2452 4600);
DISPLAY 0.872340 (-2452 4600);
PAINT GREEN (-2452 4600);
DISPLAY INVISIBLE (-2452 4600);
FORCEADD TAP..1
(-2250 4500);
FORCEPROP 3 LASTPIN (-2300 4500) SIG_NAME P5E_CPU0_P0_RX_DN<4>
J 0
(-2290 4510);
DISPLAY 0.659574 (-2290 4510);
PAINT MONO (-2290 4510);
DISPLAY INVISIBLE (-2290 4510);
FORCEPROP 1 LASTPIN (-2300 4500) BN 4
J 0
(-2312 4508);
DISPLAY 0.680851 (-2312 4508);
PAINT GREEN (-2312 4508);
FORCEPROP 2 LAST CDS_LIB standard
J 0
(-2250 4500);
DISPLAY INVISIBLE (-2250 4500);
FORCEPROP 1 LAST BODY_TYPE PLUMBING
J 0
(-2250 4550);
DISPLAY 0.872340 (-2250 4550);
PAINT GREEN (-2250 4550);
DISPLAY INVISIBLE (-2250 4550);
FORCEPROP 1 LAST HDL_TAP TRUE
J 0
(-1925 4375);
DISPLAY 0.872340 (-1925 4375);
DISPLAY INVISIBLE (-1925 4375);
FORCEPROP 1 LAST PATH I33
J 0
(-2252 4500);
DISPLAY 0.872340 (-2252 4500);
PAINT GREEN (-2252 4500);
DISPLAY INVISIBLE (-2252 4500);
FORCEADD TAP..1
(-2450 4950);
FORCEPROP 3 LASTPIN (-2500 4950) SIG_NAME P5E_CPU0_P0_RX_DP<5>
J 0
(-2490 4960);
DISPLAY 0.659574 (-2490 4960);
PAINT MONO (-2490 4960);
DISPLAY INVISIBLE (-2490 4960);
FORCEPROP 1 LASTPIN (-2500 4950) BN 5
J 0
(-2512 4958);
DISPLAY 0.680851 (-2512 4958);
PAINT GREEN (-2512 4958);
FORCEPROP 2 LAST CDS_LIB standard
J 0
(-2450 4950);
DISPLAY INVISIBLE (-2450 4950);
FORCEPROP 1 LAST BODY_TYPE PLUMBING
J 0
(-2450 5000);
DISPLAY 0.872340 (-2450 5000);
PAINT GREEN (-2450 5000);
DISPLAY INVISIBLE (-2450 5000);
FORCEPROP 1 LAST HDL_TAP TRUE
J 0
(-2125 4825);
DISPLAY 0.872340 (-2125 4825);
DISPLAY INVISIBLE (-2125 4825);
FORCEPROP 1 LAST PATH I34
J 0
(-2452 4950);
DISPLAY 0.872340 (-2452 4950);
PAINT GREEN (-2452 4950);
DISPLAY INVISIBLE (-2452 4950);
FORCEADD TAP..1
(-2250 4850);
FORCEPROP 3 LASTPIN (-2300 4850) SIG_NAME P5E_CPU0_P0_RX_DN<5>
J 0
(-2290 4860);
DISPLAY 0.659574 (-2290 4860);
PAINT MONO (-2290 4860);
DISPLAY INVISIBLE (-2290 4860);
FORCEPROP 1 LASTPIN (-2300 4850) BN 5
J 0
(-2312 4858);
DISPLAY 0.680851 (-2312 4858);
PAINT GREEN (-2312 4858);
FORCEPROP 2 LAST CDS_LIB standard
J 0
(-2250 4850);
DISPLAY INVISIBLE (-2250 4850);
FORCEPROP 1 LAST BODY_TYPE PLUMBING
J 0
(-2250 4900);
DISPLAY 0.872340 (-2250 4900);
PAINT GREEN (-2250 4900);
DISPLAY INVISIBLE (-2250 4900);
FORCEPROP 1 LAST HDL_TAP TRUE
J 0
(-1925 4725);
DISPLAY 0.872340 (-1925 4725);
DISPLAY INVISIBLE (-1925 4725);
FORCEPROP 1 LAST PATH I35
J 0
(-2252 4850);
DISPLAY 0.872340 (-2252 4850);
PAINT GREEN (-2252 4850);
DISPLAY INVISIBLE (-2252 4850);
FORCEADD TAP..1
(-2250 5200);
FORCEPROP 3 LASTPIN (-2300 5200) SIG_NAME P5E_CPU0_P0_RX_DN<6>
J 0
(-2290 5210);
DISPLAY 0.659574 (-2290 5210);
PAINT MONO (-2290 5210);
DISPLAY INVISIBLE (-2290 5210);
FORCEPROP 1 LASTPIN (-2300 5200) BN 6
J 0
(-2312 5208);
DISPLAY 0.680851 (-2312 5208);
PAINT GREEN (-2312 5208);
FORCEPROP 2 LAST CDS_LIB standard
J 0
(-2250 5200);
DISPLAY INVISIBLE (-2250 5200);
FORCEPROP 1 LAST BODY_TYPE PLUMBING
J 0
(-2250 5250);
DISPLAY 0.872340 (-2250 5250);
PAINT GREEN (-2250 5250);
DISPLAY INVISIBLE (-2250 5250);
FORCEPROP 1 LAST HDL_TAP TRUE
J 0
(-1925 5075);
DISPLAY 0.872340 (-1925 5075);
DISPLAY INVISIBLE (-1925 5075);
FORCEPROP 1 LAST PATH I36
J 0
(-2252 5200);
DISPLAY 0.872340 (-2252 5200);
PAINT GREEN (-2252 5200);
DISPLAY INVISIBLE (-2252 5200);
FORCEADD TAP..1
(-2450 5300);
FORCEPROP 3 LASTPIN (-2500 5300) SIG_NAME P5E_CPU0_P0_RX_DP<6>
J 0
(-2490 5310);
DISPLAY 0.659574 (-2490 5310);
PAINT MONO (-2490 5310);
DISPLAY INVISIBLE (-2490 5310);
FORCEPROP 1 LASTPIN (-2500 5300) BN 6
J 0
(-2512 5308);
DISPLAY 0.680851 (-2512 5308);
PAINT GREEN (-2512 5308);
FORCEPROP 2 LAST CDS_LIB standard
J 0
(-2450 5300);
DISPLAY INVISIBLE (-2450 5300);
FORCEPROP 1 LAST BODY_TYPE PLUMBING
J 0
(-2450 5350);
DISPLAY 0.872340 (-2450 5350);
PAINT GREEN (-2450 5350);
DISPLAY INVISIBLE (-2450 5350);
FORCEPROP 1 LAST HDL_TAP TRUE
J 0
(-2125 5175);
DISPLAY 0.872340 (-2125 5175);
DISPLAY INVISIBLE (-2125 5175);
FORCEPROP 1 LAST PATH I37
J 0
(-2452 5300);
DISPLAY 0.872340 (-2452 5300);
PAINT GREEN (-2452 5300);
DISPLAY INVISIBLE (-2452 5300);
FORCEADD TAP..1
(-2450 5650);
FORCEPROP 3 LASTPIN (-2500 5650) SIG_NAME P5E_CPU0_P0_RX_DP<7>
J 0
(-2490 5660);
DISPLAY 0.659574 (-2490 5660);
PAINT MONO (-2490 5660);
DISPLAY INVISIBLE (-2490 5660);
FORCEPROP 1 LASTPIN (-2500 5650) BN 7
J 0
(-2512 5658);
DISPLAY 0.680851 (-2512 5658);
PAINT GREEN (-2512 5658);
FORCEPROP 2 LAST CDS_LIB standard
J 0
(-2450 5650);
DISPLAY INVISIBLE (-2450 5650);
FORCEPROP 1 LAST BODY_TYPE PLUMBING
J 0
(-2450 5700);
DISPLAY 0.872340 (-2450 5700);
PAINT GREEN (-2450 5700);
DISPLAY INVISIBLE (-2450 5700);
FORCEPROP 1 LAST HDL_TAP TRUE
J 0
(-2125 5525);
DISPLAY 0.872340 (-2125 5525);
DISPLAY INVISIBLE (-2125 5525);
FORCEPROP 1 LAST PATH I38
J 0
(-2452 5650);
DISPLAY 0.872340 (-2452 5650);
PAINT GREEN (-2452 5650);
DISPLAY INVISIBLE (-2452 5650);
FORCEADD TAP..1
(-2250 5550);
FORCEPROP 3 LASTPIN (-2300 5550) SIG_NAME P5E_CPU0_P0_RX_DN<7>
J 0
(-2290 5560);
DISPLAY 0.659574 (-2290 5560);
PAINT MONO (-2290 5560);
DISPLAY INVISIBLE (-2290 5560);
FORCEPROP 1 LASTPIN (-2300 5550) BN 7
J 0
(-2312 5558);
DISPLAY 0.680851 (-2312 5558);
PAINT GREEN (-2312 5558);
FORCEPROP 2 LAST CDS_LIB standard
J 0
(-2250 5550);
DISPLAY INVISIBLE (-2250 5550);
FORCEPROP 1 LAST BODY_TYPE PLUMBING
J 0
(-2250 5600);
DISPLAY 0.872340 (-2250 5600);
PAINT GREEN (-2250 5600);
DISPLAY INVISIBLE (-2250 5600);
FORCEPROP 1 LAST HDL_TAP TRUE
J 0
(-1925 5425);
DISPLAY 0.872340 (-1925 5425);
DISPLAY INVISIBLE (-1925 5425);
FORCEPROP 1 LAST PATH I39
J 0
(-2252 5550);
DISPLAY 0.872340 (-2252 5550);
PAINT GREEN (-2252 5550);
DISPLAY INVISIBLE (-2252 5550);
FORCEADD TAP..1
(-6625 3075);
FORCEPROP 3 LASTPIN (-6675 3075) SIG_NAME P5E_CPU0_P0_RX_DN<8>
J 0
(-6665 3085);
DISPLAY 0.659574 (-6665 3085);
PAINT MONO (-6665 3085);
DISPLAY INVISIBLE (-6665 3085);
FORCEPROP 1 LASTPIN (-6675 3075) BN 8
J 0
(-6687 3083);
DISPLAY 0.680851 (-6687 3083);
PAINT GREEN (-6687 3083);
FORCEPROP 2 LAST CDS_LIB standard
J 0
(-6625 3075);
DISPLAY INVISIBLE (-6625 3075);
FORCEPROP 1 LAST BODY_TYPE PLUMBING
J 0
(-6625 3125);
DISPLAY 0.872340 (-6625 3125);
PAINT GREEN (-6625 3125);
DISPLAY INVISIBLE (-6625 3125);
FORCEPROP 1 LAST HDL_TAP TRUE
J 0
(-6300 2950);
DISPLAY 0.872340 (-6300 2950);
DISPLAY INVISIBLE (-6300 2950);
FORCEPROP 1 LAST PATH I4
J 0
(-6627 3075);
DISPLAY 0.872340 (-6627 3075);
PAINT GREEN (-6627 3075);
DISPLAY INVISIBLE (-6627 3075);
FORCEADD OFFPAGE..5
R 2
(-1225 5875);
FORCEPROP 2 LAST $XR0 24 
J 0
(-1036 5875);
DISPLAY 0.638298 (-1036 5875);
PAINT MONO (-1036 5875);
FORCEPROP 2 LAST CDS_LIB standard
J 0
(-1225 5875);
DISPLAY INVISIBLE (-1225 5875);
FORCEPROP 1 LAST OFFPAGE TRUE
J 2
(-1550 5750);
DISPLAY 0.872340 (-1550 5750);
PAINT GREEN (-1550 5750);
DISPLAY INVISIBLE (-1550 5750);
FORCEPROP 1 LAST COMMENT_BODY TRUE
J 2
(-1325 5800);
DISPLAY 0.872340 (-1325 5800);
PAINT GREEN (-1325 5800);
DISPLAY INVISIBLE (-1325 5800);
FORCEPROP 2 LAST PATH I42
J 0
(-1050 5950);
DISPLAY 0.680851 (-1050 5950);
DISPLAY INVISIBLE (-1050 5950);
FORCEADD OFFPAGE..5
R 2
(-1225 5775);
FORCEPROP 2 LAST $XR0 24 
J 0
(-1036 5775);
DISPLAY 0.638298 (-1036 5775);
PAINT MONO (-1036 5775);
FORCEPROP 2 LAST CDS_LIB standard
J 0
(-1225 5775);
DISPLAY INVISIBLE (-1225 5775);
FORCEPROP 1 LAST OFFPAGE TRUE
J 2
(-1550 5650);
DISPLAY 0.872340 (-1550 5650);
PAINT GREEN (-1550 5650);
DISPLAY INVISIBLE (-1550 5650);
FORCEPROP 1 LAST COMMENT_BODY TRUE
J 2
(-1325 5700);
DISPLAY 0.872340 (-1325 5700);
PAINT GREEN (-1325 5700);
DISPLAY INVISIBLE (-1325 5700);
FORCEPROP 2 LAST PATH I43
J 0
(-1050 5850);
DISPLAY 0.680851 (-1050 5850);
DISPLAY INVISIBLE (-1050 5850);
FORCEADD TAP..1
(-6825 3525);
FORCEPROP 3 LASTPIN (-6875 3525) SIG_NAME P5E_CPU0_P0_RX_DP<9>
J 0
(-6865 3535);
DISPLAY 0.659574 (-6865 3535);
PAINT MONO (-6865 3535);
DISPLAY INVISIBLE (-6865 3535);
FORCEPROP 1 LASTPIN (-6875 3525) BN 9
J 0
(-6887 3533);
DISPLAY 0.680851 (-6887 3533);
PAINT GREEN (-6887 3533);
FORCEPROP 2 LAST CDS_LIB standard
J 0
(-6825 3525);
DISPLAY INVISIBLE (-6825 3525);
FORCEPROP 1 LAST BODY_TYPE PLUMBING
J 0
(-6825 3575);
DISPLAY 0.872340 (-6825 3575);
PAINT GREEN (-6825 3575);
DISPLAY INVISIBLE (-6825 3575);
FORCEPROP 1 LAST HDL_TAP TRUE
J 0
(-6500 3400);
DISPLAY 0.872340 (-6500 3400);
DISPLAY INVISIBLE (-6500 3400);
FORCEPROP 1 LAST PATH I5
J 0
(-6827 3525);
DISPLAY 0.872340 (-6827 3525);
PAINT GREEN (-6827 3525);
DISPLAY INVISIBLE (-6827 3525);
FORCEADD TAP..1
(-6825 3875);
FORCEPROP 3 LASTPIN (-6875 3875) SIG_NAME P5E_CPU0_P0_RX_DP<10>
J 0
(-6865 3885);
DISPLAY 0.659574 (-6865 3885);
PAINT MONO (-6865 3885);
DISPLAY INVISIBLE (-6865 3885);
FORCEPROP 1 LASTPIN (-6875 3875) BN 10
J 0
(-6887 3883);
DISPLAY 0.680851 (-6887 3883);
PAINT GREEN (-6887 3883);
FORCEPROP 2 LAST CDS_LIB standard
J 0
(-6825 3875);
DISPLAY INVISIBLE (-6825 3875);
FORCEPROP 1 LAST BODY_TYPE PLUMBING
J 0
(-6825 3925);
DISPLAY 0.872340 (-6825 3925);
PAINT GREEN (-6825 3925);
DISPLAY INVISIBLE (-6825 3925);
FORCEPROP 1 LAST HDL_TAP TRUE
J 0
(-6500 3750);
DISPLAY 0.872340 (-6500 3750);
DISPLAY INVISIBLE (-6500 3750);
FORCEPROP 1 LAST PATH I6
J 0
(-6827 3875);
DISPLAY 0.872340 (-6827 3875);
PAINT GREEN (-6827 3875);
DISPLAY INVISIBLE (-6827 3875);
FORCEADD TAP..1
(-6625 3775);
FORCEPROP 3 LASTPIN (-6675 3775) SIG_NAME P5E_CPU0_P0_RX_DN<10>
J 0
(-6665 3785);
DISPLAY 0.659574 (-6665 3785);
PAINT MONO (-6665 3785);
DISPLAY INVISIBLE (-6665 3785);
FORCEPROP 1 LASTPIN (-6675 3775) BN 10
J 0
(-6687 3783);
DISPLAY 0.680851 (-6687 3783);
PAINT GREEN (-6687 3783);
FORCEPROP 2 LAST CDS_LIB standard
J 0
(-6625 3775);
DISPLAY INVISIBLE (-6625 3775);
FORCEPROP 1 LAST BODY_TYPE PLUMBING
J 0
(-6625 3825);
DISPLAY 0.872340 (-6625 3825);
PAINT GREEN (-6625 3825);
DISPLAY INVISIBLE (-6625 3825);
FORCEPROP 1 LAST HDL_TAP TRUE
J 0
(-6300 3650);
DISPLAY 0.872340 (-6300 3650);
DISPLAY INVISIBLE (-6300 3650);
FORCEPROP 1 LAST PATH I7
J 0
(-6627 3775);
DISPLAY 0.872340 (-6627 3775);
PAINT GREEN (-6627 3775);
DISPLAY INVISIBLE (-6627 3775);
FORCEADD TAP..1
(-6625 4125);
FORCEPROP 3 LASTPIN (-6675 4125) SIG_NAME P5E_CPU0_P0_RX_DN<11>
J 0
(-6665 4135);
DISPLAY 0.659574 (-6665 4135);
PAINT MONO (-6665 4135);
DISPLAY INVISIBLE (-6665 4135);
FORCEPROP 1 LASTPIN (-6675 4125) BN 11
J 0
(-6687 4133);
DISPLAY 0.680851 (-6687 4133);
PAINT GREEN (-6687 4133);
FORCEPROP 2 LAST CDS_LIB standard
J 0
(-6625 4125);
DISPLAY INVISIBLE (-6625 4125);
FORCEPROP 1 LAST BODY_TYPE PLUMBING
J 0
(-6625 4175);
DISPLAY 0.872340 (-6625 4175);
PAINT GREEN (-6625 4175);
DISPLAY INVISIBLE (-6625 4175);
FORCEPROP 1 LAST HDL_TAP TRUE
J 0
(-6300 4000);
DISPLAY 0.872340 (-6300 4000);
DISPLAY INVISIBLE (-6300 4000);
FORCEPROP 1 LAST PATH I8
J 0
(-6627 4125);
DISPLAY 0.872340 (-6627 4125);
PAINT GREEN (-6627 4125);
DISPLAY INVISIBLE (-6627 4125);
FORCEADD TAP..1
(-6825 4225);
FORCEPROP 3 LASTPIN (-6875 4225) SIG_NAME P5E_CPU0_P0_RX_DP<11>
J 0
(-6865 4235);
DISPLAY 0.659574 (-6865 4235);
PAINT MONO (-6865 4235);
DISPLAY INVISIBLE (-6865 4235);
FORCEPROP 1 LASTPIN (-6875 4225) BN 11
J 0
(-6887 4233);
DISPLAY 0.680851 (-6887 4233);
PAINT GREEN (-6887 4233);
FORCEPROP 2 LAST CDS_LIB standard
J 0
(-6825 4225);
DISPLAY INVISIBLE (-6825 4225);
FORCEPROP 1 LAST BODY_TYPE PLUMBING
J 0
(-6825 4275);
DISPLAY 0.872340 (-6825 4275);
PAINT GREEN (-6825 4275);
DISPLAY INVISIBLE (-6825 4275);
FORCEPROP 1 LAST HDL_TAP TRUE
J 0
(-6500 4100);
DISPLAY 0.872340 (-6500 4100);
DISPLAY INVISIBLE (-6500 4100);
FORCEPROP 1 LAST PATH I9
J 0
(-6827 4225);
DISPLAY 0.872340 (-6827 4225);
PAINT GREEN (-6827 4225);
DISPLAY INVISIBLE (-6827 4225);
FORCEADD QUANTA_TITLE_BLOCK_C..1
(0 0);
FORCEPROP 0 LAST CDS_CON_LAST_MODIFIED Thu Sep 14 16:12:49 2023
J 0
(-1885 15);
DISPLAY INVISIBLE (-1885 15);
FORCEPROP 1 LAST CUSTOM_TXT_CDS <CON_LAST_MODIFIED>
J 0
(-1885 15);
DISPLAY 0.978723 (-1885 15);
FORCEPROP 2 LAST CUSTOM_TXT_CDS <XR_PAGE_TITLE>
J 0
(-7890 5250);
DISPLAY 0.638298 (-7890 5250);
PAINT PINK (-7890 5250);
DISPLAY INVISIBLE (-7890 5250);
FORCEPROP 1 LAST CUSTOM_TXT_CDS <NAME_2>
J 0
(-3175 50);
FORCEPROP 1 LAST CUSTOM_TXT_CDS <NAME_1>
J 0
(-3175 175);
FORCEPROP 1 LAST CUSTOM_TXT_CDS <Q_NUMBER>
J 0
(-1403 103);
DISPLAY 1.212766 (-1403 103);
FORCEPROP 1 LAST CUSTOM_TXT_CDS <Q_PROJ>
J 0
(-2382 102);
DISPLAY 1.212766 (-2382 102);
FORCEPROP 1 LAST CUSTOM_TXT_CDS <Q_REV>
J 0
(-184 103);
DISPLAY 1.212766 (-184 103);
FORCEPROP 1 LAST CUSTOM_TXT_CDS <CON_PAGE_NUM> OF <CON_TOTAL_PAGES>
J 0
(-446 18);
DISPLAY 0.978723 (-446 18);
FORCEPROP 1 LAST Q_TITLE RETIMER_CPU0_P0(2)
J 0
(-9366 26);
DISPLAY 2.446809 (-9366 26);
PAINT GREEN (-9366 26);
FORCEPROP 1 LAST CDS_LMAN_SYM_OUTLINE -9475,6775,100,-125
J 0
(0 0);
DISPLAY 0.468085 (0 0);
PAINT GREEN (0 0);
DISPLAY INVISIBLE (0 0);
FORCEPROP 2 LAST CDS_LIB pure_quanta
J 0
(0 0);
DISPLAY INVISIBLE (0 0);
FORCEPROP 2 LAST PAGE_BORDER TRUE
J 0
(-7890 5250);
DISPLAY 0.638298 (-7890 5250);
PAINT PINK (-7890 5250);
DISPLAY INVISIBLE (-7890 5250);
FORCEPROP 2 LAST CDS_XR_PAGE_TITLE CR-274 : @T6G_MB_LIB.T6G(SCH_1):PAGE274
J 0
(-7890 5250);
DISPLAY 0.638298 (-7890 5250);
PAINT PINK (-7890 5250);
DISPLAY INVISIBLE (-7890 5250);
FORCEPROP 1 LAST Q_DEPT BU9
J 1
(-3763 49);
DISPLAY 1.957447 (-3763 49);
PAINT GREEN (-3763 49);
DISPLAY INVISIBLE (-3763 49);
FORCEPROP 1 LAST COMMENT_BODY TRUE
J 0
(12 -13);
DISPLAY 0.978723 (12 -13);
PAINT GREEN (12 -13);
DISPLAY INVISIBLE (12 -13);
WIRE 17 -1 (-6775 4950)(-6775 4600);
WIRE 17 -1 (-6775 5300)(-6775 4950);
WIRE 17 -1 (-6775 4250)(-6775 4600);
WIRE 17 -1 (-6775 4250)(-6775 3900);
WIRE 17 -1 (-6775 5650)(-6775 5300);
WIRE 17 -1 (-6775 5725)(-6775 5650);
WIRE 17 -1 (-6775 3900)(-6775 3550);
WIRE 17 -1 (-6775 3550)(-6775 3200);
WIRE 17 -1 (-6775 5725)(-5650 5725);
FORCEPROP 2 LAST SIG_NAME P5E_CPU0_P0_RX_DP<15:8>
J 0
(-6510 5735);
DISPLAY 0.680851 (-6510 5735);
PAINT WHITE (-6510 5735);
WIRE 17 -1 (-2400 4975)(-2400 4625);
WIRE 17 -1 (-2400 5325)(-2400 4975);
WIRE 17 -1 (-2400 4275)(-2400 4625);
WIRE 17 -1 (-2400 4275)(-2400 3925);
WIRE 17 -1 (-2400 5675)(-2400 5325);
WIRE 17 -1 (-2400 5875)(-2400 5675);
WIRE 17 -1 (-2400 3925)(-2400 3575);
WIRE 17 -1 (-2400 3575)(-2400 3225);
WIRE 17 -1 (-2400 5875)(-1275 5875);
FORCEPROP 2 LAST SIG_NAME P5E_CPU0_P0_RX_DP<7:0>
J 0
(-2135 5885);
DISPLAY 0.680851 (-2135 5885);
PAINT WHITE (-2135 5885);
WIRE 17 -1 (-6575 4850)(-6575 4500);
WIRE 17 -1 (-6575 5200)(-6575 4850);
WIRE 17 -1 (-6575 4150)(-6575 4500);
WIRE 17 -1 (-6575 4150)(-6575 3800);
WIRE 17 -1 (-6575 5550)(-6575 5200);
WIRE 17 -1 (-6575 5600)(-6575 5550);
WIRE 17 -1 (-6575 3800)(-6575 3450);
WIRE 17 -1 (-6575 3450)(-6575 3100);
WIRE 17 -1 (-6575 5600)(-5675 5600);
FORCEPROP 2 LAST SIG_NAME P5E_CPU0_P0_RX_DN<15:8>
J 0
(-6510 5610);
DISPLAY 0.680851 (-6510 5610);
PAINT WHITE (-6510 5610);
WIRE 17 -1 (-2200 3475)(-2200 3125);
WIRE 17 -1 (-2200 3825)(-2200 3475);
WIRE 17 -1 (-2200 4175)(-2200 3825);
WIRE 17 -1 (-2200 4175)(-2200 4525);
WIRE 17 -1 (-2200 4875)(-2200 4525);
WIRE 17 -1 (-2200 5225)(-2200 4875);
WIRE 17 -1 (-2200 5575)(-2200 5225);
WIRE 17 -1 (-2200 5775)(-2200 5575);
WIRE 17 -1 (-2200 5775)(-1275 5775);
FORCEPROP 2 LAST SIG_NAME P5E_CPU0_P0_RX_DN<7:0>
J 0
(-2135 5785);
DISPLAY 0.680851 (-2135 5785);
PAINT WHITE (-2135 5785);
WIRE 16 -1 (-7400 5625)(-6875 5625);
WIRE 16 -1 (-7400 5525)(-6675 5525);
WIRE 16 -1 (-7400 5175)(-6675 5175);
WIRE 16 -1 (-7400 5275)(-6875 5275);
WIRE 16 -1 (-3025 4150)(-2300 4150);
WIRE 16 -1 (-3025 4950)(-2500 4950);
WIRE 16 -1 (-3025 5200)(-2300 5200);
WIRE 16 -1 (-3025 5300)(-2500 5300);
WIRE 16 -1 (-3025 5550)(-2300 5550);
WIRE 16 -1 (-3025 5650)(-2500 5650);
WIRE 16 -1 (-3025 4850)(-2300 4850);
WIRE 16 -1 (-3025 4500)(-2300 4500);
WIRE 16 -1 (-3025 4250)(-2500 4250);
WIRE 16 -1 (-3025 3900)(-2500 3900);
WIRE 16 -1 (-3025 3800)(-2300 3800);
WIRE 16 -1 (-3025 3550)(-2500 3550);
WIRE 16 -1 (-3025 3450)(-2300 3450);
WIRE 16 -1 (-7400 4825)(-6675 4825);
WIRE 16 -1 (-3025 3100)(-2300 3100);
WIRE 16 -1 (-7400 3075)(-6675 3075);
WIRE 16 -1 (-7400 3775)(-6675 3775);
WIRE 16 -1 (-7400 3425)(-6675 3425);
WIRE 16 -1 (-7400 4125)(-6675 4125);
WIRE 16 -1 (-7400 4475)(-6675 4475);
WIRE 16 -1 (-3025 3200)(-2500 3200);
WIRE 16 -1 (-7400 4925)(-6875 4925);
WIRE 16 -1 (-3025 4600)(-2500 4600);
WIRE 16 -1 (-7400 3175)(-6875 3175);
WIRE 16 -1 (-7400 3525)(-6875 3525);
WIRE 16 -1 (-7400 3875)(-6875 3875);
WIRE 16 -1 (-7400 4225)(-6875 4225);
WIRE 16 -1 (-7400 4575)(-6875 4575);
FORCENOTE
P5E_CPU0_P0_RX_DP/DN<0-15> LANE REVERSAL
(-9000 6325) 0;
DISPLAY LEFT (-9000 6325);
DISPLAY 2.000000 (-9000 6325);
FORCENOTE
RETIMER TO CPU
(-3925 2625) 0;
DISPLAY LEFT (-3925 2625);
DISPLAY 3.148936 (-3925 2625);
FORCENOTE
RETIMER TO CPU
(-8200 2625) 0;
DISPLAY LEFT (-8200 2625);
DISPLAY 3.148936 (-8200 2625);
QUIT
